# BASEBOARD_FAB2 (Tioga Pass) — schematic netlist excerpt (pin names and nets, part order shuffled) for the footprints in the layout excerpt that follows; sources: Cadence DE-HDL packaged netlist, KiCad conversion of Wiwynn_Tioga_Pass_MB.brd

C6A2  CAP  10UF 4V 20% X6S  pkg 0603LF  page 232 : A = PVPP_DEF ; B = GND
R7F16  RES  22.1 1.0% CHIP  pkg 0402  page 231 : A = PWRGD_PVPP_ABC_R ; B = PWRGD_PVPP_ABC
R4C9  RES  1.00K 1% CHIP  pkg 0402  page 96 : A = GND ; B = PD_GTL2014_2_VREF

(kicad_pcb
	(version 20260206)
	(generator "pcbnew")
	(generator_version "10.0")
	(general
		(thickness 1.6)
		(legacy_teardrops no)
	)
	(paper "A4")
	(title_block
		(title "Wiwynn_Tioga_Pass_MB.brd")
		(comment 1 "Tioga Pass / footprints 787-789 of 4770")
	)
	(layers
		(0 "F.Cu" signal "TOP")
		(4 "In1.Cu" signal "L2GND")
		(6 "In2.Cu" signal "L3")
		(8 "In3.Cu" signal "L4GND")
		(10 "In4.Cu" signal "L5")
		(12 "In5.Cu" signal "L6GND")
		(14 "In6.Cu" signal "L7VCC")
		(16 "In7.Cu" signal "L8VCC")
		(18 "In8.Cu" signal "L9GND")
		(20 "In9.Cu" signal "L10")
		(22 "In10.Cu" signal "L11GND")
		(24 "In11.Cu" signal "L12")
		(26 "In12.Cu" signal "L13GND")
		(2 "B.Cu" signal "BOTTOM")
		(9 "F.Adhes" user "F.Adhesive")
		(11 "B.Adhes" user "B.Adhesive")
		(13 "F.Paste" user "Package Geometry/Pastemask Top")
		(15 "B.Paste" user "Package Geometry/Pastemask Bottom")
		(5 "F.SilkS" user "Ref Des/Silkscreen Top")
		(7 "B.SilkS" user "Ref Des/Silkscreen Bottom")
		(1 "F.Mask" user "Board Geometry/Soldermask Top")
		(3 "B.Mask" user "Board Geometry/Soldermask Bottom")
		(17 "Dwgs.User" user "User.Drawings")
		(19 "Cmts.User" user "User.Comments")
		(21 "Eco1.User" user "User.Eco1")
		(23 "Eco2.User" user "User.Eco2")
		(25 "Edge.Cuts" user "Board Geometry/Outline")
		(27 "Margin" user)
		(31 "F.CrtYd" user "Package Geometry/Place Bound Top")
		(29 "B.CrtYd" user "Package Geometry/Place Bound Bottom")
		(35 "F.Fab" user "Ref Des/Assembly Top")
		(33 "B.Fab" user "Ref Des/Assembly Bottom")
	)
	(footprint ""
		(layer "F.Cu")
		(at 175.2346 -93.3958 180)
		(property "Reference" "R4C9"
			(at 0 0 180)
			(layer "F.SilkS")
			(hide yes)
			(effects
				(font
					(size 1.27 1.27)
				)
			)
		)
		(property "Value" ""
			(at 0 0 180)
			(layer "F.Fab")
			(effects
				(font
					(size 1.27 1.27)
				)
			)
		)
		(duplicate_pad_numbers_are_jumpers no)
		(fp_poly
			(pts
				(xy -0.2794 -0.1016) (xy 0.2794 -0.1016) (xy 0.2794 0.9906) (xy -0.2794 0.9906)
			)
			(stroke
				(width 0)
				(type default)
			)
			(fill no)
			(layer "F.CrtYd")
		)
		(fp_line
			(start 0.2794 0.9906)
			(end 0.2794 -0.1016)
			(stroke
				(width 0.1)
				(type default)
			)
			(layer "F.Fab")
		)
		(fp_line
			(start 0.2794 -0.1016)
			(end -0.2794 -0.1016)
			(stroke
				(width 0.1)
				(type default)
			)
			(layer "F.Fab")
		)
		(fp_line
			(start -0.2794 0.9906)
			(end 0.2794 0.9906)
			(stroke
				(width 0.1)
				(type default)
			)
			(layer "F.Fab")
		)
		(fp_line
			(start -0.2794 -0.1016)
			(end -0.2794 0.9906)
			(stroke
				(width 0.1)
				(type default)
			)
			(layer "F.Fab")
		)
		(pad "1" smd rect
			(at 0 0 180)
			(size 0.508 0.508)
			(layers "F.Cu" "F.Mask" "F.Paste")
			(net "GND")
		)
		(pad "2" smd rect
			(at 0 0.889 180)
			(size 0.508 0.508)
			(layers "F.Cu" "F.Mask" "F.Paste")
			(net "PD_GTL2014_2_VREF")
		)
		(zone
			(layer "F.Cu")
			(hatch none 0.5)
			(connect_pads
				(clearance 0)
			)
			(min_thickness 0.25)
			(keepout
				(tracks not_allowed)
				(vias allowed)
				(pads allowed)
				(copperpour not_allowed)
				(footprints allowed)
			)
			(placement
				(enabled no)
				(sheetname "")
			)
			(fill
				(thermal_gap 0.5)
				(thermal_bridge_width 0.5)
				(island_removal_mode 0)
			)
			(polygon
				(pts
					(xy 175.4886 -94.0308) (xy 174.9806 -94.0308) (xy 174.9806 -93.6498) (xy 175.4886 -93.6498)
				)
			)
		)
		(zone
			(layer "F.Cu")
			(hatch none 0.5)
			(connect_pads
				(clearance 0)
			)
			(min_thickness 0.25)
			(keepout
				(tracks allowed)
				(vias not_allowed)
				(pads allowed)
				(copperpour not_allowed)
				(footprints allowed)
			)
			(placement
				(enabled no)
				(sheetname "")
			)
			(fill
				(thermal_gap 0.5)
				(thermal_bridge_width 0.5)
				(island_removal_mode 0)
			)
			(polygon
				(pts
					(xy 175.4886 -93.6498) (xy 174.9806 -93.6498) (xy 174.9806 -94.0308) (xy 175.4886 -94.0308)
				)
			)
		)
	)
	(footprint ""
		(layer "F.Cu")
		(at 318.543432 -149.86 -90)
		(property "Reference" "C6A2"
			(at 0 0 270)
			(layer "F.SilkS")
			(hide yes)
			(effects
				(font
					(size 1.27 1.27)
				)
			)
		)
		(property "Value" ""
			(at 0 0 270)
			(layer "F.Fab")
			(effects
				(font
					(size 1.27 1.27)
				)
			)
		)
		(duplicate_pad_numbers_are_jumpers no)
		(fp_poly
			(pts
				(xy -0.4953 -0.2032) (xy 0.4953 -0.2032) (xy 0.4953 1.6002) (xy -0.4953 1.6002)
			)
			(stroke
				(width 0)
				(type default)
			)
			(fill no)
			(layer "F.CrtYd")
		)
		(fp_line
			(start -0.4953 1.6002)
			(end -0.4953 -0.2032)
			(stroke
				(width 0.1)
				(type default)
			)
			(layer "F.Fab")
		)
		(fp_line
			(start 0.4953 1.6002)
			(end -0.4953 1.6002)
			(stroke
				(width 0.1)
				(type default)
			)
			(layer "F.Fab")
		)
		(fp_line
			(start -0.4953 -0.2032)
			(end 0.4953 -0.2032)
			(stroke
				(width 0.1)
				(type default)
			)
			(layer "F.Fab")
		)
		(fp_line
			(start 0.4953 -0.2032)
			(end 0.4953 1.6002)
			(stroke
				(width 0.1)
				(type default)
			)
			(layer "F.Fab")
		)
		(pad "1" smd rect
			(at 0 0 270)
			(size 0.762 0.889)
			(layers "F.Cu" "F.Mask" "F.Paste")
			(net "PVPP_DEF")
		)
		(pad "2" smd rect
			(at 0 1.397 270)
			(size 0.762 0.889)
			(layers "F.Cu" "F.Mask" "F.Paste")
			(net "GND")
		)
		(zone
			(layer "F.Cu")
			(hatch none 0.5)
			(connect_pads
				(clearance 0)
			)
			(min_thickness 0.25)
			(keepout
				(tracks not_allowed)
				(vias allowed)
				(pads allowed)
				(copperpour not_allowed)
				(footprints allowed)
			)
			(placement
				(enabled no)
				(sheetname "")
			)
			(fill
				(thermal_gap 0.5)
				(thermal_bridge_width 0.5)
				(island_removal_mode 0)
			)
			(polygon
				(pts
					(xy 318.098932 -150.241) (xy 318.098932 -149.479) (xy 317.590932 -149.479) (xy 317.590932 -150.241)
				)
			)
		)
	)
	(footprint ""
		(layer "F.Cu")
		(at 348.384114 -23.486618)
		(property "Reference" "R7F16"
			(at 0 0 0)
			(layer "F.SilkS")
			(hide yes)
			(effects
				(font
					(size 1.27 1.27)
				)
			)
		)
		(property "Value" ""
			(at 0 0 0)
			(layer "F.Fab")
			(effects
				(font
					(size 1.27 1.27)
				)
			)
		)
		(duplicate_pad_numbers_are_jumpers no)
		(fp_poly
			(pts
				(xy -0.2794 -0.1016) (xy 0.2794 -0.1016) (xy 0.2794 0.9906) (xy -0.2794 0.9906)
			)
			(stroke
				(width 0)
				(type default)
			)
			(fill no)
			(layer "F.CrtYd")
		)
		(fp_line
			(start -0.2794 -0.1016)
			(end -0.2794 0.9906)
			(stroke
				(width 0.1)
				(type default)
			)
			(layer "F.Fab")
		)
		(fp_line
			(start -0.2794 0.9906)
			(end 0.2794 0.9906)
			(stroke
				(width 0.1)
				(type default)
			)
			(layer "F.Fab")
		)
		(fp_line
			(start 0.2794 -0.1016)
			(end -0.2794 -0.1016)
			(stroke
				(width 0.1)
				(type default)
			)
			(layer "F.Fab")
		)
		(fp_line
			(start 0.2794 0.9906)
			(end 0.2794 -0.1016)
			(stroke
				(width 0.1)
				(type default)
			)
			(layer "F.Fab")
		)
		(pad "1" smd rect
			(at 0 0)
			(size 0.508 0.508)
			(layers "F.Cu" "F.Mask" "F.Paste")
			(net "PWRGD_PVPP_ABC_R")
		)
		(pad "2" smd rect
			(at 0 0.889)
			(size 0.508 0.508)
			(layers "F.Cu" "F.Mask" "F.Paste")
			(net "PWRGD_PVPP_ABC")
		)
		(zone
			(layer "F.Cu")
			(hatch none 0.5)
			(connect_pads
				(clearance 0)
			)
			(min_thickness 0.25)
			(keepout
				(tracks allowed)
				(vias not_allowed)
				(pads allowed)
				(copperpour not_allowed)
				(footprints allowed)
			)
			(placement
				(enabled no)
				(sheetname "")
			)
			(fill
				(thermal_gap 0.5)
				(thermal_bridge_width 0.5)
				(island_removal_mode 0)
			)
			(polygon
				(pts
					(xy 348.130114 -23.232618) (xy 348.638114 -23.232618) (xy 348.638114 -22.851618) (xy 348.130114 -22.851618)
				)
			)
		)
		(zone
			(layer "F.Cu")
			(hatch none 0.5)
			(connect_pads
				(clearance 0)
			)
			(min_thickness 0.25)
			(keepout
				(tracks not_allowed)
				(vias allowed)
				(pads allowed)
				(copperpour not_allowed)
				(footprints allowed)
			)
			(placement
				(enabled no)
				(sheetname "")
			)
			(fill
				(thermal_gap 0.5)
				(thermal_bridge_width 0.5)
				(island_removal_mode 0)
			)
			(polygon
				(pts
					(xy 348.130114 -22.851618) (xy 348.638114 -22.851618) (xy 348.638114 -23.232618) (xy 348.130114 -23.232618)
				)
			)
		)
	)
)
